5
5
4
4
3
3
2
2
1
1
D D
C C
B B
A A
Power Distribution Backplane 
Version: 2012/08/13 
PCB: DA0T6MTB8C0 
LAYER: 8 
Title 
Size Document Number Rev
Date: Sheet 
of 
Cover 1A
Power Distribution Backplane Assembly V1
Cloud Server Infrastructure Engineering
C
1 11Monday, January 27, 2014 
Title 
Size Document Number Rev
Date: Sheet 
of 
Cover 1A
Power Distribution Backplane Assembly V1
Cloud Server Infrastructure Engineering
C
1 11Monday, January 27, 2014 
Title 
Size Document Number Rev
Date: Sheet 
of 
Cover 1A
Power Distribution Backplane Assembly V1
Cloud Server Infrastructure Engineering
C
1 11Monday, January 27, 2014 



5
5
4
4
3
3
2
2
1
1
D D
C C
B B
A A
Title 
Size Document Number Rev
Date: Sheet 
of 
Block Diagram 1A
Power Distribution Backplane Assembly V1
Cloud Server Infrastructure Engineering
C
2 11Monday, January 27, 2014 
Title 
Size Document Number Rev
Date: Sheet 
of 
Block Diagram 1A
Power Distribution Backplane Assembly V1
Cloud Server Infrastructure Engineering
C
2 11Monday, January 27, 2014 
Title 
Size Document Number Rev
Date: Sheet 
of 
Block Diagram 1A
Power Distribution Backplane Assembly V1
Cloud Server Infrastructure Engineering
C
2 11Monday, January 27, 2014 



5
5
4
4
3
3
2
2
1
1
D D
C C
B B
A A
Title 
Size Document Number Rev
Date: Sheet 
of 
Stackup 1A
Power Distribution Backplane Assembly V1
Cloud Server Infrastructure Engineering
C
3 11Monday, January 27, 2014 
Title 
Size Document Number Rev
Date: Sheet 
of 
Stackup 1A
Power Distribution Backplane Assembly V1
Cloud Server Infrastructure Engineering
C
3 11Monday, January 27, 2014 
Title 
Size Document Number Rev
Date: Sheet 
of 
Stackup 1A
Power Distribution Backplane Assembly V1
Cloud Server Infrastructure Engineering
C
3 11Monday, January 27, 2014 



5
5
4
4
3
3
2
2
1
1
D D
C C
B B
A A
Title 
Size Document Number Rev
Date: Sheet 
of 
Blank 1A
Power Distribution Backplane Assembly V1
Cloud Server Infrastructure Engineering
C
4 11Monday, January 27, 2014 
Title 
Size Document Number Rev
Date: Sheet 
of 
Blank 1A
Power Distribution Backplane Assembly V1
Cloud Server Infrastructure Engineering
C
4 11Monday, January 27, 2014 
Title 
Size Document Number Rev
Date: Sheet 
of 
Blank 1A
Power Distribution Backplane Assembly V1
Cloud Server Infrastructure Engineering
C
4 11Monday, January 27, 2014 



5
5
4
4
3
3
2
2
1
1
D D
C C
B B
A A
PSU1 
PSU CONNECTOR 
Internal PU 3.3V: 
SDA:6.7K 
SCL:6.7K 
ALERT:100K 
RESET:100K 
PS_KILL:10K 
PRSNT:100 
POK:1K 
VIN_GOOD:1K 
PSU2 
Internal PU 3.3V: 
SDA:6.7K 
SCL:6.7K 
ALERT:100K 
RESET:100K 
PS_KILL:10K 
PRSNT:100 
POK:1K 
VIN_GOOD:1K 
PSU3 
PSU4 
Internal PU 3.3V: 
SDA:6.7K 
SCL:6.7K 
ALERT:100K 
RESET:100K 
PS_KILL:10K 
PRSNT:100 
POK:1K 
VIN_GOOD:1K 
Internal PU 3.3V: 
SDA:6.7K 
SCL:6.7K 
ALERT:100K 
RESET:100K 
PS_KILL:10K 
PRSNT:100 
POK:1K 
VIN_GOOD:1K 
PSU6 
Internal PU 3.3V: 
SDA:6.7K 
SCL:6.7K 
ALERT:100K 
RESET:100K 
PS_KILL:10K 
PRSNT:100 
POK:1K 
VIN_GOOD:1K 
PSU5 
Internal PU 3.3V: 
SDA:6.7K 
SCL:6.7K 
ALERT:100K 
RESET:100K 
PS_KILL:10K 
PRSNT:100 
POK:1K 
VIN_GOOD:1K 
PSU1_REMOTE_N 
PSU1_CSAHRE 
PSU1_REMOTE_P 
PSU1_AD0 
PSU1_RETURN 
PSU1_REMOTE_N 
PSU1_REMOTE_P 
PSU1_RETURN 
PSU2_REMOTE_P 
PSU2_REMOTE_N 
PSU2_RETURN 
PSU3_REMOTE_P 
PSU3_REMOTE_N 
PSU3_RETURN 
PSU4_REMOTE_P 
PSU4_REMOTE_N 
PSU4_RETURN 
PSU6_REMOTE_P 
PSU6_REMOTE_N 
PSU6_RETURN 
PSU1_AD0 
PSU4_AD0 
PSU3_AD0 
PSU2_REMOTE_N 
PSU2_CSAHRE 
PSU_ALERT_N 
PSU2_REMOTE_P 
PSU2_AD0 
PSU2_RETURN 
I2C_PSU1_SCL 
I2C_PSU1_SDA 
PSU3_REMOTE_N 
PSU3_CSAHRE 
PSU_ALERT_N 
PSU4_REMOTE_N 
PSU4_CSAHRE 
PSU_ALERT_N 
PSU3_REMOTE_P 
PSU3_AD0 
PSU3_RETURN 
PSU4_REMOTE_P 
PSU4_AD0 
PSU4_RETURN 
I2C_PSU2_SCL 
I2C_PSU2_SDA 
PSU6_REMOTE_P 
PSU6_AD0 
PSU6_RETURN 
I2C_PSU3_SCL 
I2C_PSU3_SDA 
PSU6_REMOTE_N 
PSU6_CSAHRE 
PSU_ALERT_N 
PSU5_REMOTE_P 
PSU5_REMOTE_N 
PSU5_RETURN 
PSU5_AD0 
PSU5_REMOTE_P 
PSU5_AD0 
PSU5_RETURN 
PSU5_REMOTE_N 
PSU5_CSAHRE 
PSU_ALERT_N 
PSU2_AD0 
PSU6_AD0 
PSU1_RESET 
PSU1_PS_KILL 
PSU1_PS_KILL 
PSU1_RESET PSU2_RESET 
PSU2_PS_KILL 
PSU2_RESET 
PSU2_PS_KILL 
PSU3_RESET 
PSU3_PS_KILL 
PSU3_PS_KILL 
PSU3_RESET 
PSU4_RESET 
PSU4_PS_KILL 
PSU4_RESET 
PSU4_PS_KILL 
PSU5_PS_KILL 
PSU5_RESET 
PSU5_RESET 
PSU5_PS_KILL 
PSU6_PS_KILL 
PSU6_RESET 
PSU6_RESET 
PSU6_PS_KILL 
PSU1_PS_KILL 
PSU1_RESET 
PSU2_PS_KILL 
PSU2_RESET 
PSU3_PS_KILL 
PSU3_RESET 
PSU4_PS_KILL 
PSU4_RESET 
PSU5_PS_KILL 
PSU5_RESET 
PSU6_PS_KILL 
PSU6_RESET 
PSU1_REMOTE_P 
PSU1_REMOTE_N 
PSU1_REMOTE_R_P 
PSU1_REMOTE_R_N 
PSU2_REMOTE_R_N 
PSU2_REMOTE_P 
PSU2_REMOTE_N 
PSU2_REMOTE_R_P 
PSU3_REMOTE_R_N 
PSU3_REMOTE_P 
PSU3_REMOTE_N 
PSU3_REMOTE_R_P 
PSU6_REMOTE_R_N 
PSU6_REMOTE_P 
PSU6_REMOTE_N 
PSU6_REMOTE_R_P 
PSU5_REMOTE_R_N 
PSU5_REMOTE_P 
PSU5_REMOTE_N 
PSU5_REMOTE_R_P 
PSU4_REMOTE_R_N 
PSU4_REMOTE_P 
PSU4_REMOTE_N 
PSU4_REMOTE_R_P 
PSU1_REMOTE_P PSU1_REMOTE_R2_P 
PSU1_REMOTE_R2_N PSU1_REMOTE_N 
PSU2_REMOTE_P PSU2_REMOTE_R2_P 
PSU2_REMOTE_R2_N PSU2_REMOTE_N 
PSU3_REMOTE_P PSU3_REMOTE_R2_P 
PSU3_REMOTE_R2_N PSU3_REMOTE_N 
PSU4_REMOTE_P PSU4_REMOTE_R2_P 
PSU4_REMOTE_R2_N PSU4_REMOTE_N 
PSU5_REMOTE_P PSU5_REMOTE_R2_P 
PSU5_REMOTE_R2_N PSU5_REMOTE_N 
PSU6_REMOTE_P PSU6_REMOTE_R2_P 
PSU6_REMOTE_R2_N PSU6_REMOTE_N 
PSU1_CSAHRE PSU_CSAHRE 
PSU2_CSAHRE 
PSU3_CSAHRE 
PSU4_CSAHRE 
PSU5_CSAHRE 
PSU6_CSAHRE 
PSU1_PS_ON_N (8) 
I2C_PSU1_SCL (8) 
I2C_PSU1_SDA (8) PSU_ALERT_N (8) 
PSU2_PS_ON_N (8) PSU3_PS_ON_N (8) 
PSU4_PS_ON_N (8) 
I2C_PSU2_SCL (8) 
I2C_PSU2_SDA (8) 
PSU6_PS_ON_N (8) 
I2C_PSU3_SCL (8) 
I2C_PSU3_SDA (8) 
PSU5_PS_ON_N (8) 
PSU1_AC_OK (8) PSU2_AC_OK (8) PSU3_AC_OK (8) 
PSU6_AC_OK (8) PSU5_AC_OK (8) PSU4_AC_OK (8) 
PSU4_DC_OK (8) PSU5_DC_OK (8) PSU6_DC_OK (8)
PSU1_DC_OK (8) PSU2_DC_OK (8) PSU3_DC_OK (8)
P12V P12V 
P12V_STBY 
P12V 
P12V 
P12V_STBY 
P12V 
P12V 
P12V 
P12V 
P12V_STBY 
P12V 
P12V_STBY 
P12V 
P12V 
P12V 
P12V 
P12V_STBY 
P12V 
P12V 
P12V_STBY 
P12V 
P12V_STBY 
P12V 
P12V 
P12V_STBY 
P12V_STBY 
P12V_STBY P12V_STBY
P12V_STBY 
P12V_STBY 
P12V_STBY 
P12V_STBY 
P12V_STBY 
P12V_STBY
P12V_STBY
P12V_STBY 
P12V_STBY 
P12V_STBY 
P12V_STBY 
P12V_STBY
P12V_STBY 
P12V 
P12V 
P12V 
P12V 
P12V 
P12V 
Title 
Size Document Number Rev
Date: Sheet 
of 
PSU Connector 1A
Power Distribution Backplane Assembly V1
Cloud Server Infrastructure Engineering
C
5 11Monday, January 27, 2014 
Title 
Size Document Number Rev
Date: Sheet 
of 
PSU Connector 1A
Power Distribution Backplane Assembly V1
Cloud Server Infrastructure Engineering
C
5 11Monday, January 27, 2014 
Title 
Size Document Number Rev
Date: Sheet 
of 
PSU Connector 1A
Power Distribution Backplane Assembly V1
Cloud Server Infrastructure Engineering
C
5 11Monday, January 27, 2014 
R12 100 
R72 22.1K 
1% R0402 
NI 
R114 0
R0402 1% 
R75 8.2K 
5% R0402 
NI 
R42 100K NI 
R1 0
R0402 1% 
NI 
R97 0
R0402 1% 
NI 
R44 100K 
CHIP 
NI 
R62 22.1K 
1% R0402 
NI 
R65 8.2K 
5% R0402 
NI 
R25 100 
R83 8.2K 
5% R0402 
NI 
R121 0
R0402 1% 
R77 8.2K 
5% R0402 
NI 
R26 100 
R4 22.1K 
1% R0402 
R128 0
R0402 1% 
R94 0
R0402 1% 
NI 
R119 0
R0402 1% 
R58 100 
R84 22.1K 
1% R0402 
NI 
R134 0
R0402 1% 
R43 100 
R132 0
R0402 1% 
R78 22.1K 
1% R0402 
NI 
R118 0
R0402 1% 
R46 100 
R108 0
R0402 1% 
NI 
R100 0
R0402 1% 
NI 
R110 0
R0402 1% 
R21 8.2K 
5% R0402 
R109 0
R0402 1% 
NI 
R60 100 
R23 8.2K 
5% R0402 
R106 0
R0402 1% 
NI 
R69 8.2K 
5% R0402 
NI 
R47 100 
R91 0
R0402 1% 
NI 
R70 22.1K 
1% R0402 
NI 
R120 0
R0402 1% 
R20 0
R0402 1% 
NI 
R89 0
R0402 1% 
NI 
R73 8.2K 
5% R0402 
NI 
R22 0
R0402 1% 
NI 
R107 0
R0402 1% 
NI 
R55 100 
R14 0
R0402 1% 
NI 
R138 0
R0402 1% 
R27 100 
R80 22.1K 
1% R0402 
NI 
R64 22.1K 
1% R0402 
NI 
R113 0
R0402 1% 
J1 
10046971-001LF 
REMOTE SENSE- 26 
VIN_GOOD 27 
CSHARE 28 
-PS_ON 29 
PS_KILL 30 
RESET 31 
ALERT 32 
TACH 25 REMOTE SENSE+ 40 
12V_SB 39 
PS_A0 38 
POK 37 
RETURN 36 
SCL 35 
-PS_PRESENT 34 
SDA 33 
+12V_1 1
+12V_2 2
+12V_3 3
+12V_4 4
+12V_5 5
+12V_6 6
+12V_7 7
+12V_8 8
+12V_9 9
+12V_10 10 
+12V_11 11 
+12V_12 12 
+12V_24 64 
+12V_23 63 
+12V_22 62 
+12V_21 61 
+12V_20 60 
+12V_19 59 
+12V_18 58 
+12V_17 57 
+12V_16 56 
+12V_15 55 
+12V_14 54 
+12V_13 53 
RTN1 13 
RTN2 14 
RTN3 15 
RTN4 16 
RTN5 17 
RTN6 18 
RTN7 19 
RTN8 20 
RTN9 21 
RTN10 22 
RTN11 23 
RTN12 24 
RTN24 52 
RTN23 51 
RTN22 50 
RTN21 49 
RTN20 48 
RTN19 47 
RTN18 46 
RTN17 45 
RTN16 44 
RTN15 43 
RTN14 42 
RTN13 41 
R13 100 
R137 0
R0402 1% 
R5 0
R0402 1% 
NI 
R40 100K 
R6 0
R0402 1% 
NI 
R139 0
R0402 1% 
J5 
10046971-001LF 
REMOTE SENSE- 26 
VIN_GOOD 27 
CSHARE 28 
-PS_ON 29 
PS_KILL 30 
RESET 31 
ALERT 32 
TACH 25 REMOTE SENSE+ 40 
12V_SB 39 
PS_A0 38 
POK 37 
RETURN 36 
SCL 35 
-PS_PRESENT 34 
SDA 33 
+12V_1 1
+12V_2 2
+12V_3 3
+12V_4 4
+12V_5 5
+12V_6 6
+12V_7 7
+12V_8 8
+12V_9 9
+12V_10 10 
+12V_11 11 
+12V_12 12 
+12V_24 64 
+12V_23 63 
+12V_22 62 
+12V_21 61 
+12V_20 60 
+12V_19 59 
+12V_18 58 
+12V_17 57 
+12V_16 56 
+12V_15 55 
+12V_14 54 
+12V_13 53 
RTN1 13 
RTN2 14 
RTN3 15 
RTN4 16 
RTN5 17 
RTN6 18 
RTN7 19 
RTN8 20 
RTN9 21 
RTN10 22 
RTN11 23 
RTN12 24 
RTN24 52 
RTN23 51 
RTN22 50 
RTN21 49 
RTN20 48 
RTN19 47 
RTN18 46 
RTN17 45 
RTN16 44 
RTN15 43 
RTN14 42 
RTN13 41 
R82 22.1K 
1% R0402 
NI 
R11 100 
R7 0
R0402 1% 
NI 
J3 
10046971-001LF 
REMOTE SENSE- 26 
VIN_GOOD 27 
CSHARE 28 
-PS_ON 29 
PS_KILL 30 
RESET 31 
ALERT 32 
TACH 25 REMOTE SENSE+ 40 
12V_SB 39 
PS_A0 38 
POK 37 
RETURN 36 
SCL 35 
-PS_PRESENT 34 
SDA 33 
+12V_1 1
+12V_2 2
+12V_3 3
+12V_4 4
+12V_5 5
+12V_6 6
+12V_7 7
+12V_8 8
+12V_9 9
+12V_10 10 
+12V_11 11 
+12V_12 12 
+12V_24 64 
+12V_23 63 
+12V_22 62 
+12V_21 61 
+12V_20 60 
+12V_19 59 
+12V_18 58 
+12V_17 57 
+12V_16 56 
+12V_15 55 
+12V_14 54 
+12V_13 53 
RTN1 13 
RTN2 14 
RTN3 15 
RTN4 16 
RTN5 17 
RTN6 18 
RTN7 19 
RTN8 20 
RTN9 21 
RTN10 22 
RTN11 23 
RTN12 24 
RTN24 52 
RTN23 51 
RTN22 50 
RTN21 49 
RTN20 48 
RTN19 47 
RTN18 46 
RTN17 45 
RTN16 44 
RTN15 43 
RTN14 42 
RTN13 41 
R67 8.2K 
5% R0402 
NI R8 8.2K 
5% R0402 
R10 100 
R123 0
R0402 1% 
R79 8.2K 
5% R0402 
NI 
R86 0
R0402 1% 
NI 
R104 0
R0402 1% 
NI 
R87 0
R0402 1% 
NI 
R2 0
R0402 1% 
NI 
R93 0
R0402 1% 
NI 
J2 
10046971-001LF 
REMOTE SENSE- 26 
VIN_GOOD 27 
CSHARE 28 
-PS_ON 29 
PS_KILL 30 
RESET 31 
ALERT 32 
TACH 25 REMOTE SENSE+ 40 
12V_SB 39 
PS_A0 38 
POK 37 
RETURN 36 
SCL 35 
-PS_PRESENT 34 
SDA 33 
+12V_1 1
+12V_2 2
+12V_3 3
+12V_4 4
+12V_5 5
+12V_6 6
+12V_7 7
+12V_8 8
+12V_9 9
+12V_10 10 
+12V_11 11 
+12V_12 12 
+12V_24 64 
+12V_23 63 
+12V_22 62 
+12V_21 61 
+12V_20 60 
+12V_19 59 
+12V_18 58 
+12V_17 57 
+12V_16 56 
+12V_15 55 
+12V_14 54 
+12V_13 53 
RTN1 13 
RTN2 14 
RTN3 15 
RTN4 16 
RTN5 17 
RTN6 18 
RTN7 19 
RTN8 20 
RTN9 21 
RTN10 22 
RTN11 23 
RTN12 24 
RTN24 52 
RTN23 51 
RTN22 50 
RTN21 49 
RTN20 48 
RTN19 47 
RTN18 46 
RTN17 45 
RTN16 44 
RTN15 43 
RTN14 42 
RTN13 41 
R99 0
R0402 1% 
NI 
R56 100 
R130 0
R0402 1% 
R96 0
R0402 1% 
NI 
R131 0
R0402 1% 
R59 100 
R68 22.1K 
1% R0402 
NI 
R45 100 
R16 22.1K 
1% R0402 
R63 8.2K 
5% R0402 
NI 
R3 0
R0402 1% 
NI 
R112 0
R0402 1% 
R136 0
R0402 1% 
R57 100 
R90 0
R0402 1% 
NI 
R71 8.2K 
5% R0402 
NI 
R74 22.1K 
1% R0402 
NI 
R101 0
R0402 1% 
NI 
R88 0
R0402 1% 
NI 
R125 0
R0402 1% 
R126 0
R0402 1% 
R18 22.1K 
1% R0402 
R19 0
R0402 1% 
NI 
R98 0
R0402 1% 
NI 
R24 100 
R117 0
R0402 1% 
R103 0
R0402 1% 
NI 
R61 100 
R127 0
R0402 1% 
R76 22.1K 
1% R0402 
NI 
R81 8.2K 
5% R0402 
NI 
R95 0
R0402 1% 
NI 
R124 0
R0402 1% 
R17 0
R0402 1% 
NI 
R105 0
R0402 1% 
NI 
R85 8.2K 
5% R0402 
NI 
R15 0
R0402 1% 
NI 
R66 22.1K 
1% R0402 
NI 
R122 0
R0402 1% 
R115 0
R0402 1% 
J4 
10046971-001LF 
REMOTE SENSE- 26 
VIN_GOOD 27 
CSHARE 28 
-PS_ON 29 
PS_KILL 30 
RESET 31 
ALERT 32 
TACH 25 REMOTE SENSE+ 40 
12V_SB 39 
PS_A0 38 
POK 37 
RETURN 36 
SCL 35 
-PS_PRESENT 34 
SDA 33 
+12V_1 1
+12V_2 2
+12V_3 3
+12V_4 4
+12V_5 5
+12V_6 6
+12V_7 7
+12V_8 8
+12V_9 9
+12V_10 10 
+12V_11 11 
+12V_12 12 
+12V_24 64 
+12V_23 63 
+12V_22 62 
+12V_21 61 
+12V_20 60 
+12V_19 59 
+12V_18 58 
+12V_17 57 
+12V_16 56 
+12V_15 55 
+12V_14 54 
+12V_13 53 
RTN1 13 
RTN2 14 
RTN3 15 
RTN4 16 
RTN5 17 
RTN6 18 
RTN7 19 
RTN8 20 
RTN9 21 
RTN10 22 
RTN11 23 
RTN12 24 
RTN24 52 
RTN23 51 
RTN22 50 
RTN21 49 
RTN20 48 
RTN19 47 
RTN18 46 
RTN17 45 
RTN16 44 
RTN15 43 
RTN14 42 
RTN13 41 
R48 100 
R129 0
R0402 1% 
R111 0
R0402 1% 
J6 
10046971-001LF 
REMOTE SENSE- 26 
VIN_GOOD 27 
CSHARE 28 
-PS_ON 29 
PS_KILL 30 
RESET 31 
ALERT 32 
TACH 25 REMOTE SENSE+ 40 
12V_SB 39 
PS_A0 38 
POK 37 
RETURN 36 
SCL 35 
-PS_PRESENT 34 
SDA 33 
+12V_1 1
+12V_2 2
+12V_3 3
+12V_4 4
+12V_5 5
+12V_6 6
+12V_7 7
+12V_8 8
+12V_9 9
+12V_10 10 
+12V_11 11 
+12V_12 12 
+12V_24 64 
+12V_23 63 
+12V_22 62 
+12V_21 61 
+12V_20 60 
+12V_19 59 
+12V_18 58 
+12V_17 57 
+12V_16 56 
+12V_15 55 
+12V_14 54 
+12V_13 53 
RTN1 13 
RTN2 14 
RTN3 15 
RTN4 16 
RTN5 17 
RTN6 18 
RTN7 19 
RTN8 20 
RTN9 21 
RTN10 22 
RTN11 23 
RTN12 24 
RTN24 52 
RTN23 51 
RTN22 50 
RTN21 49 
RTN20 48 
RTN19 47 
RTN18 46 
RTN17 45 
RTN16 44 
RTN15 43 
RTN14 42 
RTN13 41 
R102 0
R0402 1% 
NI 
R133 0
R0402 1% 
R92 0
R0402 1% 
NI 
R135 0
R0402 1% 
R116 0
R0402 1% 
R9 100 



5
5
4
4
3
3
2
2
1
1
D D
C C
B B
A A
TRAY 1 TRAY 2 TRAY 3 
TRAY 4 TRAY 5 TRAY 6 
FOR TRAY1 FOR TRAY2 FOR TRAY3 FOR TRAY4 
FOR TRAY5 FOR TRAY6 
T2_BLAD2_EN (8) 
T2_BLAD3_TXD (8) 
T2_BLAD3_EN (8) 
T2_BLAD4_TXD (8) 
T2_BLAD4_EN (8) 
T2_BLAD1_TXD (8) 
T2_BLAD1_EN (8) 
T2_BLAD2_TXD (8) 
T2_BLAD2_RXD (8) 
T2_BLAD1_RXD (8) T2_BLAD3_RXD (8) 
T2_BLAD4_RXD (8) 
T3_BLAD2_EN (8) 
T3_BLAD3_TXD (8) 
T3_BLAD3_EN (8) 
T3_BLAD4_TXD (8) 
T3_BLAD3_RXD (8) 
T3_BLAD4_EN (8) 
T3_BLAD1_TXD (8) 
T3_BLAD1_RXD (8) 
T3_BLAD4_RXD (8) 
T3_BLAD1_EN (8) 
T3_BLAD2_TXD (8) 
T3_BLAD2_RXD (8) 
T4_BLAD2_EN (8) 
T4_BLAD3_TXD (8) 
T4_BLAD3_EN (8) 
T4_BLAD4_TXD (8) 
T4_BLAD3_RXD (8) 
T4_BLAD4_EN (8) 
T4_BLAD1_TXD (8) 
T4_BLAD1_RXD (8) 
T4_BLAD4_RXD (8) 
T4_BLAD1_EN (8) 
T4_BLAD2_TXD (8) 
T4_BLAD2_RXD (8) 
T6_BLAD2_EN (8) 
T6_BLAD3_TXD (8) 
T6_BLAD3_EN (8) 
T6_BLAD4_TXD (8) 
T6_BLAD3_RXD (8) 
T6_BLAD4_EN (8) 
T6_BLAD1_TXD (8) 
T6_BLAD1_RXD (8) 
T6_BLAD4_RXD (8) 
T6_BLAD1_EN (8) 
T6_BLAD2_TXD (8) 
T6_BLAD2_RXD (8) 
T1_BLAD2_EN (8) 
T1_BLAD3_TXD (8) 
T1_BLAD3_EN (8) 
T1_BLAD4_TXD (8) 
T1_BLAD3_RXD (8) 
T1_BLAD4_EN (8) 
T1_BLAD1_TXD (8) 
T1_BLAD1_RXD (8) 
T1_BLAD4_RXD (8) 
T1_BLAD1_EN (8) 
T1_BLAD2_TXD (8) 
T1_BLAD2_RXD (8) 
T5_BLAD2_EN (8) 
T5_BLAD3_TXD (8) 
T5_BLAD3_EN (8) 
T5_BLAD4_TXD (8) 
T5_BLAD3_RXD (8) 
T5_BLAD4_EN (8) 
T5_BLAD1_TXD (8) 
T5_BLAD1_RXD (8) 
T5_BLAD4_RXD (8) 
T5_BLAD1_EN (8) 
T5_BLAD2_TXD (8) 
T5_BLAD2_RXD (8) 
P12V P12V P12V 
P12V 
P12V P12V P12V 
P12V P12V P12V P12V 
P12V P12V 
P12V P12V P12V 
P12V P12V P12V 
Title 
Size Document Number Rev
Date: Sheet 
of 
Tray Connector 1 1A
Power Distribution Backplane Assembly V1
Cloud Server Infrastructure Engineering
C
6 11Monday, January 27, 2014 
Title 
Size Document Number Rev
Date: Sheet 
of 
Tray Connector 1 1A
Power Distribution Backplane Assembly V1
Cloud Server Infrastructure Engineering
C
6 11Monday, January 27, 2014 
Title 
Size Document Number Rev
Date: Sheet 
of 
Tray Connector 1 1A
Power Distribution Backplane Assembly V1
Cloud Server Infrastructure Engineering
C
6 11Monday, January 27, 2014 
C39 
0.1UF 
25V 
C0402 
+ CE10 
470UF 
16V 
1 2
+ CE11 
470UF 
16V 
1 2
C16 
0.1UF 
25V 
C0402 
C19 
0.1UF 
25V 
C0402 
C31 
0.1UF 
25V 
C0402 
Signal 
SEG1 
SEG2 
SEG3 
SEG4 SEG5 
SEG6 
SEG7 
SEG8 
PRESS-FIT 
ORIENTATION KEY 
J7 
CONN44_10117936003LF 
S3 S3 
S4 S4 
S5 S5 
S6 S6 
S12 S12 
S11 S11 
S10 S10 
S9 S9 
S8 S8 
S7 S7 
P16 P16 P15 P15 P14 P14 P13 P13 
P1 P1 
P2 P2 
P3 P3 
P12 P12 P11 P11 P10 P10 P9 P9 
P5 P5 
P6 P6 
P7 P7 
P8 P8 
S2 S2 S1 S1 
P4 P4 
P17 P17 P18 P18 P19 P19 P20 P20 
P21 P21 P22 P22 P23 P23 P24 P24 
P25 P25 P26 P26 P27 P27 P28 P28 
P29 P29 P30 P30 P31 P31 P32 P32 
C36 
1UF 
25V 
C0603 
Signal 
SEG1 
SEG2 
SEG3 
SEG4 SEG5 
SEG6 
SEG7 
SEG8 
PRESS-FIT 
ORIENTATION KEY 
J11 
CONN44_10117936003LF 
S3 S3 
S4 S4 
S5 S5 
S6 S6 
S12 S12 
S11 S11 
S10 S10 
S9 S9 
S8 S8 
S7 S7 
P16 P16 P15 P15 P14 P14 P13 P13 
P1 P1 
P2 P2 
P3 P3 
P12 P12 P11 P11 P10 P10 P9 P9 
P5 P5 
P6 P6 
P7 P7 
P8 P8 
S2 S2 S1 S1 
P4 P4 
P17 P17 P18 P18 P19 P19 P20 P20 
P21 P21 P22 P22 P23 P23 P24 P24 
P25 P25 P26 P26 P27 P27 P28 P28 
P29 P29 P30 P30 P31 P31 P32 P32 
C29 
1UF 
25V 
C0603 
C38 
0.1UF 
25V 
C0402 
+ CE3 
470UF 
16V 
1 2
C17 
0.1UF 
25V 
C0402 
+ CE7 
470UF 
16V 
1 2
C42 
100PF 
50V 
C0402 
C22 
1UF 
25V 
C0603 
Signal 
SEG1 
SEG2 
SEG3 
SEG4 SEG5 
SEG6 
SEG7 
SEG8 
PRESS-FIT 
ORIENTATION KEY 
J8 
CONN44_10117936003LF 
S3 S3 
S4 S4 
S5 S5 
S6 S6 
S12 S12 
S11 S11 
S10 S10 
S9 S9 
S8 S8 
S7 S7 
P16 P16 P15 P15 P14 P14 P13 P13 
P1 P1 
P2 P2 
P3 P3 
P12 P12 P11 P11 P10 P10 P9 P9 
P5 P5 
P6 P6 
P7 P7 
P8 P8 
S2 S2 S1 S1 
P4 P4 
P17 P17 P18 P18 P19 P19 P20 P20 
P21 P21 P22 P22 P23 P23 P24 P24 
P25 P25 P26 P26 P27 P27 P28 P28 
P29 P29 P30 P30 P31 P31 P32 P32 
C28 
100PF
50V 
C0402
C21 
100PF 
50V 
C0402 
C14 
100PF 
50V 
C0402 
+ CE5 
470UF 
16V 
1 2
C12 
0.1UF 
25V 
C0402 
+ CE4 
470UF 
16V 
1 2
C7 
100PF 
50V 
C0402 
Signal 
SEG1 
SEG2 
SEG3 
SEG4 SEG5 
SEG6 
SEG7 
SEG8 
PRESS-FIT 
ORIENTATION KEY 
J12 
CONN44_10117936003LF 
S3 S3 
S4 S4 
S5 S5 
S6 S6 
S12 S12 
S11 S11 
S10 S10 
S9 S9 
S8 S8 
S7 S7 
P16 P16 P15 P15 P14 P14 P13 P13 
P1 P1 
P2 P2 
P3 P3 
P12 P12 P11 P11 P10 P10 P9 P9 
P5 P5 
P6 P6 
P7 P7 
P8 P8 
S2 S2 S1 S1 
P4 P4 
P17 P17 P18 P18 P19 P19 P20 P20 
P21 P21 P22 P22 P23 P23 P24 P24 
P25 P25 P26 P26 P27 P27 P28 P28 
P29 P29 P30 P30 P31 P31 P32 P32 
C34 
0.1UF 
25V 
C0402 
C2 
0.1UF 
25V 
C0402 
C5 
0.1UF 
25V 
C0402 
C1 
1UF 
25V 
C0603 
C32 
0.1UF 
25V 
C0402 
C41 
0.1UF 
25V 
C0402 
+ CE12 
470UF 
16V 
1 2
C24 
0.1UF 
25V 
C0402 
Signal 
SEG1 
SEG2 
SEG3 
SEG4 SEG5 
SEG6 
SEG7 
SEG8 
PRESS-FIT 
ORIENTATION KEY 
J9 
CONN44_10117936003LF 
S3 S3 
S4 S4 
S5 S5 
S6 S6 
S12 S12 
S11 S11 
S10 S10 
S9 S9 
S8 S8 
S7 S7 
P16 P16 P15 P15 P14 P14 P13 P13 
P1 P1 
P2 P2 
P3 P3 
P12 P12 P11 P11 P10 P10 P9 P9 
P5 P5 
P6 P6 
P7 P7 
P8 P8 
S2 S2 S1 S1 
P4 P4 
P17 P17 P18 P18 P19 P19 P20 P20 
P21 P21 P22 P22 P23 P23 P24 P24 
P25 P25 P26 P26 P27 P27 P28 P28 
P29 P29 P30 P30 P31 P31 P32 P32 
C11 
0.1UF 
25V 
C0402 
+ CE1 
470UF 
16V 
1 2
C4 
0.1UF 
25V 
C0402 
+ CE9 
470UF 
16V 
1 2
+ CE2 
470UF 
16V 
1 2
+ CE8 
470UF 
16V 
1 2
C30 
0.1UF 
25V 
C0402 
C33 
0.1UF 
25V 
C0402 
C10 
0.1UF 
25V 
C0402 
C9 
0.1UF 
25V 
C0402 
C15 
1UF 
25V 
C0603 
C25 
0.1UF 
25V 
C0402 
C35 
100PF 
50V 
C0402 
C37 
0.1UF 
25V 
C0402 
C40 
0.1UF 
25V 
C0402 
C3 
0.1UF 
25V 
C0402 
C18 
0.1UF 
25V 
C0402 
C13 
0.1UF 
25V 
C0402 
Signal 
SEG1 
SEG2 
SEG3 
SEG4 SEG5 
SEG6 
SEG7 
SEG8 
PRESS-FIT 
ORIENTATION KEY 
J10 
CONN44_10117936003LF 
S3 S3 
S4 S4 
S5 S5 
S6 S6 
S12 S12 
S11 S11 
S10 S10 
S9 S9 
S8 S8 
S7 S7 
P16 P16 P15 P15 P14 P14 P13 P13 
P1 P1 
P2 P2 
P3 P3 
P12 P12 P11 P11 P10 P10 P9 P9 
P5 P5 
P6 P6 
P7 P7 
P8 P8 
S2 S2 S1 S1 
P4 P4 
P17 P17 P18 P18 P19 P19 P20 P20 
P21 P21 P22 P22 P23 P23 P24 P24 
P25 P25 P26 P26 P27 P27 P28 P28 
P29 P29 P30 P30 P31 P31 P32 P32 
+ CE6 
470UF 
16V 
1 2
C27 
0.1UF 
25V 
C0402 
C20 
0.1UF 
25V 
C0402 
C8 
1UF 
25V 
C0603 
C23 
0.1UF 
25V 
C0402 
C6 
0.1UF 
25V 
C0402 
C26 
0.1UF 
25V 
C0402 



5
5
4
4
3
3
2
2
1
1
D D
C C
B B
A A
TRAY 7 TRAY 8 TRAY 9 
TRAY 10 TRAY 11 TRAY 12 
FOR TRAY7 FOR TRAY8 FOR TRAY9 FOR TRAY10 
FOR TRAY11 FOR TRAY12 
T7_BLAD2_EN (8) 
T7_BLAD3_TXD (8) 
T7_BLAD3_EN (8) 
T7_BLAD4_TXD (8) 
T7_BLAD1_TXD (8) 
T7_BLAD1_RXD (8) T7_BLAD3_RXD (8) 
T7_BLAD4_EN (8) 
T7_BLAD1_EN (8) 
T7_BLAD2_TXD (8) 
T7_BLAD2_RXD (8) T7_BLAD4_RXD (8) 
T8_BLAD2_EN (8) 
T8_BLAD3_TXD (8) 
T8_BLAD3_EN (8) 
T8_BLAD4_TXD (8) 
T8_BLAD3_RXD (8) 
T8_BLAD4_EN (8) 
T8_BLAD1_TXD (8) 
T8_BLAD1_RXD (8) 
T8_BLAD4_RXD (8) 
T8_BLAD1_EN (8) 
T8_BLAD2_TXD (8) 
T8_BLAD2_RXD (8) 
T9_BLAD2_EN (8) 
T9_BLAD3_TXD (8) 
T9_BLAD3_EN (8) 
T9_BLAD4_TXD (8) 
T9_BLAD3_RXD (8) 
T9_BLAD1_TXD (8) 
T9_BLAD1_RXD (8) 
T9_BLAD4_EN (8) 
T9_BLAD4_RXD (8) 
T9_BLAD1_EN (8) 
T9_BLAD2_TXD (8) 
T9_BLAD2_RXD (8) 
T10_BLAD3_TXD (8) 
T10_BLAD3_EN (8) 
T10_BLAD2_EN (8) 
T10_BLAD4_TXD (8) 
T10_BLAD3_RXD (8) 
T10_BLAD4_EN (8) 
T10_BLAD4_RXD (8) 
T10_BLAD1_TXD (8) 
T10_BLAD1_RXD (8) 
T10_BLAD1_EN (8) 
T10_BLAD2_TXD (8) 
T10_BLAD2_RXD (8) 
T11_BLAD2_EN (8) 
T11_BLAD3_TXD (8) 
T11_BLAD3_EN (8) 
T11_BLAD4_TXD (8) 
T11_BLAD3_RXD (8) 
T11_BLAD4_EN (8) 
T11_BLAD1_TXD (8) 
T11_BLAD1_RXD (8) 
T11_BLAD4_RXD (8) 
T11_BLAD1_EN (8) 
T11_BLAD2_TXD (8) 
T11_BLAD2_RXD (8) 
T12_BLAD2_EN (8) 
T12_BLAD3_TXD (8) 
T12_BLAD3_EN (8) 
T12_BLAD4_TXD (8) 
T12_BLAD3_RXD (8) 
T12_BLAD4_EN (8) 
T12_BLAD1_TXD (8) 
T12_BLAD1_RXD (8) 
T12_BLAD1_EN (8) 
T12_BLAD4_RXD (8) 
T12_BLAD2_TXD (8) 
T12_BLAD2_RXD (8) 
P12V P12V 
P12V 
P12V P12V P12V 
P12V P12V P12V P12V 
P12V P12V 
P12V P12V P12V P12V 
P12V P12V P12V 
Title 
Size Document Number Rev
Date: Sheet 
of 
Tray Connector 2 1A
Power Distribution Backplane Assembly V1
Cloud Server Infrastructure Engineering
C
7 11Monday, January 27, 2014 
Title 
Size Document Number Rev
Date: Sheet 
of 
Tray Connector 2 1A
Power Distribution Backplane Assembly V1
Cloud Server Infrastructure Engineering
C
7 11Monday, January 27, 2014 
Title 
Size Document Number Rev
Date: Sheet 
of 
Tray Connector 2 1A
Power Distribution Backplane Assembly V1
Cloud Server Infrastructure Engineering
C
7 11Monday, January 27, 2014 
+ CE18 
470UF 
16V 
1 2
Signal 
SEG1 
SEG2 
SEG3 
SEG4 SEG5 
SEG6 
SEG7 
SEG8 
PRESS-FIT 
ORIENTATION KEY 
J13 
CONN44_10117936003LF 
S3 S3 
S4 S4 
S5 S5 
S6 S6 
S12 S12 
S11 S11 
S10 S10 
S9 S9 
S8 S8 
S7 S7 
P16 P16 P15 P15 P14 P14 P13 P13 
P1 P1 
P2 P2 
P3 P3 
P12 P12 P11 P11 P10 P10 P9 P9 
P5 P5 
P6 P6 
P7 P7 
P8 P8 
S2 S2 S1 S1 
P4 P4 
P17 P17 P18 P18 P19 P19 P20 P20 
P21 P21 P22 P22 P23 P23 P24 P24 
P25 P25 P26 P26 P27 P27 P28 P28 
P29 P29 P30 P30 P31 P31 P32 P32 
C76 
0.1UF 
25V 
C0402 
C61 
0.1UF 
25V 
C0402 
C51 
0.1UF 
25V 
C0402 
Signal 
SEG1 
SEG2 
SEG3 
SEG4 SEG5 
SEG6 
SEG7 
SEG8 
PRESS-FIT 
ORIENTATION KEY 
J17 
CONN44_10117936003LF 
S3 S3 
S4 S4 
S5 S5 
S6 S6 
S12 S12 
S11 S11 
S10 S10 
S9 S9 
S8 S8 
S7 S7 
P16 P16 P15 P15 P14 P14 P13 P13 
P1 P1 
P2 P2 
P3 P3 
P12 P12 P11 P11 P10 P10 P9 P9 
P5 P5 
P6 P6 
P7 P7 
P8 P8 
S2 S2 S1 S1 
P4 P4 
P17 P17 P18 P18 P19 P19 P20 P20 
P21 P21 P22 P22 P23 P23 P24 P24 
P25 P25 P26 P26 P27 P27 P28 P28 
P29 P29 P30 P30 P31 P31 P32 P32 
+ CE16 
470UF 
16V 
1 2
C68 
0.1UF 
25V 
C0402 
+ CE13 
470UF 
16V 
1 2
C82 
0.1UF 
25V 
C0402 
+ CE19 
470UF 
16V 
1 2
C43 
1UF 
25V 
C0603 
C46 
0.1UF 
25V 
C0402 
Signal 
SEG1 
SEG2 
SEG3 
SEG4 SEG5 
SEG6 
SEG7 
SEG8 
PRESS-FIT 
ORIENTATION KEY 
J14 
CONN44_10117936003LF 
S3 S3 
S4 S4 
S5 S5 
S6 S6 
S12 S12 
S11 S11 
S10 S10 
S9 S9 
S8 S8 
S7 S7 
P16 P16 P15 P15 P14 P14 P13 P13 
P1 P1 
P2 P2 
P3 P3 
P12 P12 P11 P11 P10 P10 P9 P9 
P5 P5 
P6 P6 
P7 P7 
P8 P8 
S2 S2 S1 S1 
P4 P4 
P17 P17 P18 P18 P19 P19 P20 P20 
P21 P21 P22 P22 P23 P23 P24 P24 
P25 P25 P26 P26 P27 P27 P28 P28 
P29 P29 P30 P30 P31 P31 P32 P32 
C72 
0.1UF 
25V 
C0402 
C63 
100PF 
50V 
C0402 
+ CE23 
470UF 
16V 
1 2
C50 
1UF 
25V 
C0603 
C62 
0.1UF 
25V 
C0402 
C53 
0.1UF 
25V 
C0402 
C70 
100PF
50V 
C0402
C69 
0.1UF 
25V 
C0402 
C84 
100PF 
50V 
C0402 
C45 
0.1UF 
25V 
C0402 
C71 
1UF 
25V 
C0603 
C83 
0.1UF 
25V 
C0402 
Signal 
SEG1 
SEG2 
SEG3 
SEG4 SEG5 
SEG6 
SEG7 
SEG8 
PRESS-FIT 
ORIENTATION KEY 
J18 
CONN44_10117936003LF 
S3 S3 
S4 S4 
S5 S5 
S6 S6 
S12 S12 
S11 S11 
S10 S10 
S9 S9 
S8 S8 
S7 S7 
P16 P16 P15 P15 P14 P14 P13 P13 
P1 P1 
P2 P2 
P3 P3 
P12 P12 P11 P11 P10 P10 P9 P9 
P5 P5 
P6 P6 
P7 P7 
P8 P8 
S2 S2 S1 S1 
P4 P4 
P17 P17 P18 P18 P19 P19 P20 P20 
P21 P21 P22 P22 P23 P23 P24 P24 
P25 P25 P26 P26 P27 P27 P28 P28 
P29 P29 P30 P30 P31 P31 P32 P32 
C74 
0.1UF 
25V 
C0402 
C58 
0.1UF 
25V 
C0402 
C52 
0.1UF 
25V 
C0402 
+ CE17 
470UF 
16V 
1 2
C65 
0.1UF 
25V 
C0402 
Signal 
SEG1 
SEG2 
SEG3 
SEG4 SEG5 
SEG6 
SEG7 
SEG8 
PRESS-FIT 
ORIENTATION KEY 
J15 
CONN44_10117936003LF 
S3 S3 
S4 S4 
S5 S5 
S6 S6 
S12 S12 
S11 S11 
S10 S10 
S9 S9 
S8 S8 
S7 S7 
P16 P16 P15 P15 P14 P14 P13 P13 
P1 P1 
P2 P2 
P3 P3 
P12 P12 P11 P11 P10 P10 P9 P9 
P5 P5 
P6 P6 
P7 P7 
P8 P8 
S2 S2 S1 S1 
P4 P4 
P17 P17 P18 P18 P19 P19 P20 P20 
P21 P21 P22 P22 P23 P23 P24 P24 
P25 P25 P26 P26 P27 P27 P28 P28 
P29 P29 P30 P30 P31 P31 P32 P32 
+ CE15 
470UF 
16V 
1 2
+ CE21 
470UF 
16V 
1 2
C47 
0.1UF 
25V 
C0402 
C79 
0.1UF 
25V 
C0402 
C73 
0.1UF 
25V 
C0402 
C57 
1UF 
25V 
C0603 
C54 
0.1UF 
25V 
C0402 
+ CE20 
470UF 
16V 
1 2
C64 
1UF 
25V 
C0603 
+ CE22 
470UF 
16V 
1 2
C60 
0.1UF 
25V 
C0402 
C78 
1UF 
25V 
C0603 
C49 
100PF 
50V 
C0402 
+ CE24 
470UF 
16V 
1 2
C67 
0.1UF 
25V 
C0402 
C48 
0.1UF 
25V 
C0402 
Signal 
SEG1 
SEG2 
SEG3 
SEG4 SEG5 
SEG6 
SEG7 
SEG8 
PRESS-FIT 
ORIENTATION KEY 
J16 
CONN44_10117936003LF 
S3 S3 
S4 S4 
S5 S5 
S6 S6 
S12 S12 
S11 S11 
S10 S10 
S9 S9 
S8 S8 
S7 S7 
P16 P16 P15 P15 P14 P14 P13 P13 
P1 P1 
P2 P2 
P3 P3 
P12 P12 P11 P11 P10 P10 P9 P9 
P5 P5 
P6 P6 
P7 P7 
P8 P8 
S2 S2 S1 S1 
P4 P4 
P17 P17 P18 P18 P19 P19 P20 P20 
P21 P21 P22 P22 P23 P23 P24 P24 
P25 P25 P26 P26 P27 P27 P28 P28 
P29 P29 P30 P30 P31 P31 P32 P32 
C75 
0.1UF 
25V 
C0402 
C81 
0.1UF 
25V 
C0402 
+ CE14 
470UF 
16V 
1 2
C56 
100PF 
50V 
C0402 
C59 
0.1UF 
25V 
C0402 
C55 
0.1UF 
25V 
C0402 
C66 
0.1UF 
25V 
C0402 
C44 
0.1UF 
25V 
C0402 
C77 
100PF 
50V 
C0402 
C80 
0.1UF 
25V 
C0402 



5
5
4
4
3
3
2
2
1
1
D D
C C
B B
A A
MATE_A1 
POWER_SW3_PWR_CTR_12V 
POWER_SW2_PWR_CTR_12V 
POWER_SW1_PWR_CTR_12V 
CM_PWR_CTL_IN 
MATE_A1 
POWER_SW3_PWR_CTR_12V 
POWER_SW2_PWR_CTR_12V 
POWER_SW1_PWR_CTR_12V 
CM_PWR_CTL_IN 
LAN2_P3_P (10) 
LAN2_P3_N (10) 
LAN2_P4_P (10) 
LAN2_P4_N (10) 
UART_TX_RP6_L (10) 
UART_CTS_RP6_L_N (10) 
UART_DTR_RP6_L_N (10) 
UART_RI_RP6_L_N (10) 
FAN4_TACH (9) 
FAN5_TACH (9) 
FAN6_TACH (9) 
FAN_PWM (9) 
T11_BLAD1_EN (7) 
T11_BLAD2_EN (7) 
T11_BLAD3_EN (7) 
T11_BLAD4_EN (7) 
I2C_PSU3_SDA (5) 
I2C_PSU3_SCL (5) 
T11_BLAD1_TXD (7) 
T11_BLAD1_RXD (7) 
T11_BLAD2_TXD (7) 
T11_BLAD2_RXD (7) 
T11_BLAD3_TXD (7) 
T11_BLAD3_RXD (7) 
T11_BLAD4_RXD (7) 
T11_BLAD4_TXD (7) 
T9_BLAD3_EN (7) 
T9_BLAD4_EN (7) 
T9_BLAD1_EN (7) 
T9_BLAD2_EN (7) 
T9_BLAD1_TXD (7) 
T9_BLAD1_RXD (7) 
T9_BLAD2_TXD (7) 
T9_BLAD2_RXD (7) 
T9_BLAD3_RXD (7) 
T9_BLAD3_TXD (7) 
T9_BLAD4_RXD (7) 
T9_BLAD4_TXD (7) 
T7_BLAD1_EN (7) 
T7_BLAD2_EN (7) 
T7_BLAD3_EN (7) 
T7_BLAD4_EN (7) 
T7_BLAD2_RXD (7) 
T7_BLAD2_TXD (7) 
T7_BLAD1_RXD (7) 
T7_BLAD1_TXD (7) 
T7_BLAD3_TXD (7) 
T7_BLAD3_RXD (7) 
T7_BLAD4_RXD (7) 
T7_BLAD4_TXD (7) 
PSU_ALERT_N (5) 
T5_BLAD2_EN (6) 
T5_BLAD1_EN (6) 
T5_BLAD4_EN (6) 
T5_BLAD3_EN (6) 
T5_BLAD1_RXD (6) 
T5_BLAD1_TXD (6) 
T5_BLAD2_RXD (6) 
T5_BLAD2_TXD (6) 
T5_BLAD3_RXD (6) 
T5_BLAD3_TXD (6) 
LAN1_P1_P (10) 
LAN1_P1_N (10) 
LAN1_P2_P (10) 
LAN1_P2_N (10) 
LAN2_P1_P (10) 
LAN2_P1_N (10) 
LAN2_P2_P (10) 
LAN2_P2_N (10) 
I2C_PDB_SCL (9) 
I2C_PDB_SDA (9) 
UART_DTR_RP5_L_N (10) 
UART_RI_RP5_L_N (10) 
UART_TX_RP5_L (10) 
UART_CTS_RP5_L_N (10) 
FAN1_TACH (9) 
FAN2_TACH (9) 
FAN3_TACH (9) 
T12_BLAD1_EN (7) 
T12_BLAD2_EN (7) 
T12_BLAD3_EN (7) 
T12_BLAD4_EN (7) 
T12_BLAD1_TXD (7) 
T12_BLAD1_RXD (7) 
T12_BLAD2_TXD (7) 
T12_BLAD2_RXD (7) 
T12_BLAD3_RXD (7) 
T12_BLAD3_TXD (7) 
T12_BLAD4_RXD (7) 
T12_BLAD4_TXD (7) 
T10_BLAD1_EN (7) 
T10_BLAD2_EN (7) 
T10_BLAD3_EN (7) 
T10_BLAD4_EN (7) 
T10_BLAD1_TXD (7) 
T10_BLAD1_RXD (7) 
T10_BLAD2_TXD (7) 
T10_BLAD2_RXD (7) 
T10_BLAD3_RXD (7) 
T10_BLAD3_TXD (7) 
T10_BLAD4_RXD (7) 
T10_BLAD4_TXD (7) 
T8_BLAD1_EN (7) 
T8_BLAD2_EN (7) 
T8_BLAD3_EN (7) 
T8_BLAD4_EN (7) 
T8_BLAD1_RXD (7) 
T8_BLAD1_TXD (7) 
T8_BLAD2_RXD (7) 
T8_BLAD2_TXD (7) 
T8_BLAD3_RXD (7) 
T8_BLAD3_TXD (7) 
T8_BLAD4_RXD (7) 
T8_BLAD4_TXD (7) 
T6_BLAD2_EN (6) 
T6_BLAD1_EN (6) 
T6_BLAD4_EN (6) 
T6_BLAD3_EN (6) 
T6_BLAD1_RXD (6) 
T6_BLAD1_TXD (6) 
T6_BLAD2_RXD (6) 
T6_BLAD2_TXD (6) 
T6_BLAD3_RXD (6) 
T6_BLAD3_TXD (6) 
T6_BLAD4_RXD (6) 
T6_BLAD4_TXD (6) 
I2C_PSU2_SCL (5) 
I2C_PSU2_SDA (5) 
LAN1_P3_P (10) 
LAN1_P3_N (10) 
LAN1_P4_P (10) 
LAN1_P4_N (10) 
UART_RX_RP5_L (10) 
UART_RX_RP6_L (10) 
PSU1_PS_ON_N (5) 
PSU2_PS_ON_N (5) 
PSU3_PS_ON_N (5) 
PSU4_PS_ON_N (5) 
PSU5_PS_ON_N (5) 
PSU6_PS_ON_N (5) 
UART_RTS_RP6_L_N (10) 
UART_DSR_RP6_L (10) UART_RTS_RP5_L_N (10) 
UART_DSR_RP5_L (10) 
T5_BLAD4_RXD (6) 
T5_BLAD4_TXD (6) 
T3_BLAD1_EN (6) 
T3_BLAD2_EN (6) 
T3_BLAD3_EN (6) 
T3_BLAD4_EN (6) 
T3_BLAD1_RXD (6) 
T3_BLAD1_TXD (6) 
T3_BLAD2_RXD (6) 
T3_BLAD2_TXD (6) 
T3_BLAD3_RXD (6) 
T3_BLAD3_TXD (6) 
T3_BLAD4_RXD (6) 
T3_BLAD4_TXD (6) 
T1_BLAD1_EN (6) 
T1_BLAD2_EN (6) 
T1_BLAD3_EN (6) 
T1_BLAD4_EN (6) 
PSU1_DC_OK (5) 
PSU2_DC_OK (5) 
PSU3_DC_OK (5) 
PSU4_DC_OK (5) 
PSU5_DC_OK (5) 
PSU6_DC_OK (5) 
T4_BLAD1_EN (6) 
T4_BLAD2_EN (6) 
T4_BLAD3_EN (6) 
T4_BLAD4_EN (6) 
T4_BLAD1_RXD (6) 
T4_BLAD1_TXD (6) 
T4_BLAD2_RXD (6) 
T4_BLAD2_TXD (6) 
T4_BLAD3_RXD (6) 
T4_BLAD3_TXD (6) 
T4_BLAD4_RXD (6) 
T4_BLAD4_TXD (6) 
T2_BLAD2_EN (6) 
T2_BLAD3_EN (6) 
T2_BLAD4_EN (6) 
T2_BLAD1_EN (6) 
T2_BLAD1_RXD (6) 
T2_BLAD1_TXD (6) 
T2_BLAD2_RXD (6) 
T2_BLAD2_TXD (6) 
T2_BLAD3_RXD (6) 
T2_BLAD3_TXD (6) 
T2_BLAD4_RXD (6) 
T2_BLAD4_TXD (6) 
I2C_PSU1_SCL (5) 
I2C_PSU1_SDA (5) 
PSU1_AC_OK (5) 
PSU2_AC_OK (5) 
PSU3_AC_OK (5) 
PSU4_AC_OK (5) 
PSU5_AC_OK (5) 
PSU6_AC_OK (5) 
UART_RTS_P5_L_N (10) 
UART_TX_P5_L (10) 
UART_CTS_P5_L_N (10) 
UART_DSR_P5_L_N (10) 
UART_RX_P5_L (10) 
UART_DTR_P5_L_N (10) 
UART_RI_P5_L_N (10) 
UART_TX_P1_L (10) 
UART_CTS_P1_L_N (10) 
UART_RX_P1_L (10) 
UART_DTR_P1_L_N (10) 
UART_RTS_P1_L_N (10) 
UART_DSR_P1_L_N (10) 
UART_RI_P6_L_N (10) 
UART_RTS_P6_L_N (10) 
UART_DSR_P6_L_N (10) 
UART_RX_P6_L (10) 
UART_DTR_P6_L_N (10) 
UART_TX_P6_L (10) 
UART_CTS_P6_L_N (10) 
UART_DSR_P2_L_N (10) 
UART_RX_P2_L (10) 
UART_DTR_P2_L_N (10) 
UART_TX_P2_L (10) 
UART_CTS_P2_L_N (10) 
UART_RTS_P2_L_N (10) 
T1_BLAD1_RXD (6) 
T1_BLAD1_TXD (6) 
T1_BLAD2_RXD (6) 
T1_BLAD2_TXD (6) 
T1_BLAD3_RXD (6) 
T1_BLAD3_TXD (6) 
T1_BLAD4_RXD (6) 
T1_BLAD4_TXD (6) 
P12V 
P3V3 
P12V 
Title 
Size Document Number Rev
Date: Sheet 
of 
CMC Connector 1A
Power Distribution Backplane Assembly V1
Cloud Server Infrastructure Engineering
C
8 11Monday, January 27, 2014 
Title 
Size Document Number Rev
Date: Sheet 
of 
CMC Connector 1A
Power Distribution Backplane Assembly V1
Cloud Server Infrastructure Engineering
C
8 11Monday, January 27, 2014 
Title 
Size Document Number Rev
Date: Sheet 
of 
CMC Connector 1A
Power Distribution Backplane Assembly V1
Cloud Server Infrastructure Engineering
C
8 11Monday, January 27, 2014 
R54 560 
KEY
J26 
PCIEX16 
12V_1 B1 
12V_2 B2 
12V_3 B3 
GND1 B4 
SMCLK B5 
SMDATA B6 
GND2 B7 
3.3V_1 B8 
JTAG1 B9 
3.3VAUX B10 
WAKE_N B11 
RSVD1 B12 
GND3 B13 
HSOP0+ B14 
HSOP0- B15 
GND4 B16 
PRSNT2_N-1 B17 
GND5 B18 
HSOP1+ B19 
HSOP1- B20 
GND6 B21 
GND7 B22 
HSOP2+ B23 
HSOP2- B24 
GND8 B25 
GND9 B26 
HSOP3+ B27 
HSOP3- B28 
GND10 B29 
RSVD2 B30 
PRSNT2_N-2 B31 
GND11 B32 
HSOP4+ B33 
HSOP4- B34 
GND12 B35 
GND13 B36 
HSOP5+ B37 
HSOP5- B38 
GND14 B39 
GND15 B40 
HSOP6+ B41 
HSOP6- B42 
GND16 B43 
GND17 B44 
HSOP7+ B45 
HSOP7- B46 
GND18 B47 
PRSNT2_N-3 B48 
GND19 B49 
PRSNT1_N A1 
12V_4 A2 
12V_5 A3 
GND35 A4 
JTAG2 A5 
JTAG3 A6 
JTAG4 A7 
JTAG5 A8 
3.3V_2 A9 
3.3V_3 A10 
PERST# A11 
GND36 A12 
REFCLK+ A13 
REFCLK- A14 
GND37 A15 
HSIP0+ A16 
HSIP0- A17 
GND38 A18 
RSVD4 A19 
GND39 A20 
HSIP1+ A21 
HSIP1- A22 
GND40 A23 
GND41 A24 
HSIP2+ A25 
HSIP2- A26 
GND42 A27 
GND43 A28 
HSIP3+ A29 
HSIP3- A30 
GND44 A31 
RSVD5 A32 
RSVD6 A33 
GND45 A34 
HSIP4+ A35 
HSIP4- A36 
GND46 A37 
GND47 A38 
HSIP5+ A39 
HSIP5- A40 
GND48 A41 
GND49 A42 
HSIP6+ A43 
HSIP6- A44 
GND50 A45 
GND51 A46 
HSIP7+ A47 
HSIP7- A48 
GND52 A49 
RSVD7 A50 
GND53 A51 
HSIP8+ A52 
HSIP8- A53 
GND54 A54 
GND55 A55 
HSIP9+ A56 
HSIP9- A57 
GND56 A58 
GND57 A59 
HSIP10+ A60 
HSIP10- A61 
GND58 A62 
GND59 A63 
HSIP11+ A64 
HSIP11- A65 
GND60 A66 
RSVD8 A67 
HSIP12+ A68 
HSIP12- A69 
GND61 A70 
GND62 A71 
HSIP13+ A72 
HSIP13- A73 
GND63 A74 
GND64 A75 
HSIP14 A76 
HSIP14- A77 
GND65 A78 
GND66 A79 
HSIP15+ A80 
HSIP15- A81 
GND67 A82 
HSOP8+ B50 
HSOP8- B51 
GND20 B52 
GND21 B53 
HSOP9+ B54 
HSOP9- B55 
GND22 B56 
GND23 B57 
HSOP10+ B58 
HSOP10- B59 
GND24 B60 
GND25 B61 
HSOP11+ B62 
HSOP11- B63 
GND26 B64 
GND27 B65 
HSOP12+ B66 
HSOP12- B67 
GND28 B68 
GND29 B69 
HSOP13+ B70 
HSOP13- B71 
GND30 B72 
GND31 B73 
HSOP14+ B74 
HSOP14- B75 
GND32 B76 
GND33 B77 
HSOP15+ B78 
HSOP15- B79 
GND34 B80 
PRSNT2_N-4 B81 
RSVD3 B82 
J32 
CONN2_7218102TW00 
1 2
R49 560 
KEY
J25 
PCIEX16 
12V_1 B1 
12V_2 B2 
12V_3 B3 
GND1 B4 
SMCLK B5 
SMDATA B6 
GND2 B7 
3.3V_1 B8 
JTAG1 B9 
3.3VAUX B10 
WAKE_N B11 
RSVD1 B12 
GND3 B13 
HSOP0+ B14 
HSOP0- B15 
GND4 B16 
PRSNT2_N-1 B17 
GND5 B18 
HSOP1+ B19 
HSOP1- B20 
GND6 B21 
GND7 B22 
HSOP2+ B23 
HSOP2- B24 
GND8 B25 
GND9 B26 
HSOP3+ B27 
HSOP3- B28 
GND10 B29 
RSVD2 B30 
PRSNT2_N-2 B31 
GND11 B32 
HSOP4+ B33 
HSOP4- B34 
GND12 B35 
GND13 B36 
HSOP5+ B37 
HSOP5- B38 
GND14 B39 
GND15 B40 
HSOP6+ B41 
HSOP6- B42 
GND16 B43 
GND17 B44 
HSOP7+ B45 
HSOP7- B46 
GND18 B47 
PRSNT2_N-3 B48 
GND19 B49 
PRSNT1_N A1 
12V_4 A2 
12V_5 A3 
GND35 A4 
JTAG2 A5 
JTAG3 A6 
JTAG4 A7 
JTAG5 A8 
3.3V_2 A9 
3.3V_3 A10 
PERST# A11 
GND36 A12 
REFCLK+ A13 
REFCLK- A14 
GND37 A15 
HSIP0+ A16 
HSIP0- A17 
GND38 A18 
RSVD4 A19 
GND39 A20 
HSIP1+ A21 
HSIP1- A22 
GND40 A23 
GND41 A24 
HSIP2+ A25 
HSIP2- A26 
GND42 A27 
GND43 A28 
HSIP3+ A29 
HSIP3- A30 
GND44 A31 
RSVD5 A32 
RSVD6 A33 
GND45 A34 
HSIP4+ A35 
HSIP4- A36 
GND46 A37 
GND47 A38 
HSIP5+ A39 
HSIP5- A40 
GND48 A41 
GND49 A42 
HSIP6+ A43 
HSIP6- A44 
GND50 A45 
GND51 A46 
HSIP7+ A47 
HSIP7- A48 
GND52 A49 
RSVD7 A50 
GND53 A51 
HSIP8+ A52 
HSIP8- A53 
GND54 A54 
GND55 A55 
HSIP9+ A56 
HSIP9- A57 
GND56 A58 
GND57 A59 
HSIP10+ A60 
HSIP10- A61 
GND58 A62 
GND59 A63 
HSIP11+ A64 
HSIP11- A65 
GND60 A66 
RSVD8 A67 
HSIP12+ A68 
HSIP12- A69 
GND61 A70 
GND62 A71 
HSIP13+ A72 
HSIP13- A73 
GND63 A74 
GND64 A75 
HSIP14 A76 
HSIP14- A77 
GND65 A78 
GND66 A79 
HSIP15+ A80 
HSIP15- A81 
GND67 A82 
HSOP8+ B50 
HSOP8- B51 
GND20 B52 
GND21 B53 
HSOP9+ B54 
HSOP9- B55 
GND22 B56 
GND23 B57 
HSOP10+ B58 
HSOP10- B59 
GND24 B60 
GND25 B61 
HSOP11+ B62 
HSOP11- B63 
GND26 B64 
GND27 B65 
HSOP12+ B66 
HSOP12- B67 
GND28 B68 
GND29 B69 
HSOP13+ B70 
HSOP13- B71 
GND30 B72 
GND31 B73 
HSOP14+ B74 
HSOP14- B75 
GND32 B76 
GND33 B77 
HSOP15+ B78 
HSOP15- B79 
GND34 B80 
PRSNT2_N-4 B81 
RSVD3 B82 
R52 560 
R50 560 
J33 
CONN2_7218102TW00 
1 2
J31 
CONN2_7218102TW00 
1 2
R53 560 
R51 560 
J30 
CONN2_7218102TW00 
1 2



5
5
4
4
3
3
2
2
1
1
D D
C C
B B
A A
RATED CURRENT 4.0 ( 5.2MAX.) Amp. 
RATED POWER     48 ( 62.4MAX.) Watt. 
FAN 1 ~ 6 
remeber to change correct molex connector 
ADDRESS = A2 
RESERVE 
I2C PU @ CM
FAN_PWM FAN1_TACH 
FAN2_TACH 
FAN3_TACH 
FAN4_TACH 
FAN5_TACH 
FAN6_TACH 
FRU_WP 
FRU_A0 
FRU_A1 
FRU_A2 
FRU_WP 
FRU_A0 FRU_A1 FRU_A2 
FAN5_TACH (8) 
FAN6_TACH (8) 
FAN1_TACH (8) 
FAN2_TACH (8) 
FAN3_TACH (8) 
FAN4_TACH (8) 
FAN_PWM (8) 
I2C_PDB_SCL (8) 
I2C_PDB_SDA (8) 
P12V P12V 
P12V 
P3V3 
P3V3 
P3V3 
P3V3 P3V3 
Title 
Size Document Number Rev
Date: Sheet 
of 
Fan & RM Connector 1A
Power Distribution Backplane Assembly V1
Cloud Server Infrastructure Engineering
C
9 11Monday, January 27, 2014 
Title 
Size Document Number Rev
Date: Sheet 
of 
Fan & RM Connector 1A
Power Distribution Backplane Assembly V1
Cloud Server Infrastructure Engineering
C
9 11Monday, January 27, 2014 
Title 
Size Document Number Rev
Date: Sheet 
of 
Fan & RM Connector 1A
Power Distribution Backplane Assembly V1
Cloud Server Infrastructure Engineering
C
9 11Monday, January 27, 2014 
J20 
CONN20_39281203 
11
22
33
44
55
66
77
88
99
10 10 
11 11 
12 12 
13 13 
14 14 
15 15 
16 16 
17 17 
18 18 
19 19 
20 20 
R143 8.2K 
5% R0402 
R35 3.3K 
5% R0402 
NI 
R146 8.2K 
5% R0402 
R145 8.2K 
5% R0402 
R141 22.1K 
1% R0402 
R147 8.2K 
5% R0402 
R38 100 NI R37 100 NI 
R144 8.2K 
5% R0402 
R39 100 NI 
R34 3.3K 
5% R0402 
NI 
R142 8.2K 
5% R0402 
U1 
AT24C128BN-SH-T 
NI 
VCC 8
WP 7
SCL 6
SDA 5 GND 4A2 3A1 2A0 1
R140 8.2K 
5% R0402 
R36 3.3K 
5% R0402 
NI 
R41 10K 
5% R0402 
NI 



5
5
4
4
3
3
2
2
1
1
D D
C C
B B
A A
UART_RTS_RP5_L_N (8) 
UART_DSR_RP5_L (8) 
LAN2_P1_N (8) 
LAN2_P1_P (8) 
LAN2_P4_N (8) 
LAN2_P4_P (8) 
LAN2_P2_P (8) 
LAN1_P2_P (8) 
LAN1_P1_N (8) 
LAN1_P1_P (8) 
LAN1_P4_N (8) 
LAN1_P4_P (8) 
UART_RTS_P1_L_N (8) 
UART_DSR_P1_L_N (8) 
UART_RX_P1_L (8) 
UART_TX_P1_L (8) 
UART_DTR_P1_L_N (8) 
UART_CTS_P1_L_N (8) 
UART_RTS_P2_L_N (8) 
UART_DSR_P2_L_N (8) 
UART_RX_P2_L (8) 
UART_TX_P2_L (8) 
UART_DTR_P2_L_N (8) 
UART_CTS_P2_L_N (8) 
UART_RX_RP5_L (8) 
UART_RI_RP5_L_N (8) 
UART_TX_RP5_L (8) 
UART_CTS_RP5_L_N (8) 
UART_DTR_RP5_L_N (8) 
UART_RTS_RP6_L_N (8) 
UART_RX_RP6_L (8) 
UART_DTR_RP6_L_N (8) 
UART_DSR_RP6_L (8) 
UART_TX_RP6_L (8) 
UART_CTS_RP6_L_N (8) 
UART_RI_RP6_L_N (8) 
UART_RTS_P5_L_N (8) 
UART_DSR_P5_L_N (8) 
UART_RI_P5_L_N (8) 
UART_RX_P5_L (8) 
UART_TX_P5_L (8) 
UART_CTS_P5_L_N (8) 
UART_DTR_P5_L_N (8) 
UART_RTS_P6_L_N (8) 
UART_DSR_P6_L_N (8) 
UART_RI_P6_L_N (8) 
UART_RX_P6_L (8) 
UART_TX_P6_L (8) 
UART_CTS_P6_L_N (8) 
UART_DTR_P6_L_N (8) 
LAN2_P2_N (8) 
LAN2_P3_N (8) 
LAN2_P3_P (8) 
LAN1_P3_N (8) 
LAN1_P2_N (8) 
LAN1_P3_P (8) 
Title 
Size Document Number Rev
Date: Sheet 
of 
SDC Connector 1A
Power Distribution Backplane Assembly V1
Cloud Server Infrastructure Engineering
C
10 11Monday, January 27, 2014 
Title 
Size Document Number Rev
Date: Sheet 
of 
SDC Connector 1A
Power Distribution Backplane Assembly V1
Cloud Server Infrastructure Engineering
C
10 11Monday, January 27, 2014 
Title 
Size Document Number Rev
Date: Sheet 
of 
SDC Connector 1A
Power Distribution Backplane Assembly V1
Cloud Server Infrastructure Engineering
C
10 11Monday, January 27, 2014 
R150 100 
12345678
J27 
CONN8_55692841 
1
2
3
4
5
6
7
8
R148 100 
12345678
J21 
CONN8_55692841 
1
2
3
4
5
6
7
8
12345678
J22 
CONN8_55692841 
1
2
3
4
5
6
7
8
R149 100 
R151 100 
12345678
J24 
CONN8_55692841 
1
2
3
4
5
6
7
8
12345678
910 
Orange 
Green 
11 12 
Green 
J28 
CONN12_G71B0250100EU 
9
10 
1
2
3
4
5
6
7
8
12 
11 
G1 
G2 
R152 100 
12345678
J19 
CONN8_55692841 
1
2
3
4
5
6
7
8
R153 100 
12345678
910 
Orange 
Green 
11 12 
Green 
J29 
CONN12_G71B0250100EU 
9
10 
1
2
3
4
5
6
7
8
12 
11 
G1 
G2 
12345678
J23 
CONN8_55692841 
1
2
3
4
5
6
7
8



5
5
4
4
3
3
2
2
1
1
D D
C C
B B
A A
Title 
Size Document Number Rev
Date: Sheet 
of 
Screw Holes 1A
Power Distribution Backplane Assembly V1
Cloud Server Infrastructure Engineering
C
11 11Monday, January 27, 2014 
Title 
Size Document Number Rev
Date: Sheet 
of 
Screw Holes 1A
Power Distribution Backplane Assembly V1
Cloud Server Infrastructure Engineering
C
11 11Monday, January 27, 2014 
Title 
Size Document Number Rev
Date: Sheet 
of 
Screw Holes 1A
Power Distribution Backplane Assembly V1
Cloud Server Infrastructure Engineering
C
11 11Monday, January 27, 2014 
H21 
D8N 
H7 
GNDHOLE_8PIN 
H20 
D8N 
H26 
D8N 
H10 
GNDHOLE_8PIN 
H14 
HOLE_D5-2N 
H17 
D8N 
H16 
D8N 
H24 
D8N 
H3 
GNDHOLE_8PIN 
H2 
GNDHOLE_8PIN 
H13 
HOLE_OB5-2X6-2N 
H4 
GNDHOLE_8PIN 
H22 
D8N 
H15 
D8N 
H6 
GNDHOLE_8PIN 
H9 
GNDHOLE_8PIN 
H1 
GNDHOLE_8PIN 
H12 
GNDHOLE_8PIN 
H18 
D8N 
H19 
D8N 
H25 
D8N H11 
GNDHOLE_8PIN 
H8 
GNDHOLE_8PIN 
H5 
GNDHOLE_8PIN 
H23 
D8N 